(kicad_pcb
	(version 20260206)
	(generator "pcbnew")
	(generator_version "10.0")
	(general
		(thickness 1.6)
		(legacy_teardrops no)
	)
	(paper "A4")
	(title_block
		(title "03242023_DA0F0TMBIJ0_F0T_Motherboard_J_brd_V01_OCP.brd")
		(comment 1 "Grand Teton / footprints 73-78 of 6105")
	)
	(layers
		(0 "F.Cu" signal "TOP")
		(4 "In1.Cu" signal "GND")
		(6 "In2.Cu" signal "IN1")
		(8 "In3.Cu" signal "GND1")
		(10 "In4.Cu" signal "IN2")
		(12 "In5.Cu" signal "GND2")
		(14 "In6.Cu" signal "IN3")
		(16 "In7.Cu" signal "GND3")
		(18 "In8.Cu" signal "VCC")
		(20 "In9.Cu" signal "VCC1")
		(22 "In10.Cu" signal "GND4")
		(24 "In11.Cu" signal "IN4")
		(26 "In12.Cu" signal "GND5")
		(28 "In13.Cu" signal "IN5")
		(30 "In14.Cu" signal "GND6")
		(32 "In15.Cu" signal "IN6")
		(34 "In16.Cu" signal "GND7")
		(2 "B.Cu" signal "BOTTOM")
		(9 "F.Adhes" user "F.Adhesive")
		(11 "B.Adhes" user "B.Adhesive")
		(13 "F.Paste" user "Package Geometry/Pastemask Top")
		(15 "B.Paste" user "Package Geometry/Pastemask Bottom")
		(5 "F.SilkS" user "Ref Des/Silkscreen Top")
		(7 "B.SilkS" user "Ref Des/Silkscreen Bottom")
		(1 "F.Mask" user "Board Geometry/Soldermask Top")
		(3 "B.Mask" user "Board Geometry/Soldermask Bottom")
		(17 "Dwgs.User" user "User.Drawings")
		(19 "Cmts.User" user "User.Comments")
		(21 "Eco1.User" user "User.Eco1")
		(23 "Eco2.User" user "User.Eco2")
		(25 "Edge.Cuts" user "Board Geometry/Outline")
		(27 "Margin" user)
		(31 "F.CrtYd" user "Package Geometry/Place Bound Top")
		(29 "B.CrtYd" user "Package Geometry/Place Bound Bottom")
		(35 "F.Fab" user "Ref Des/Assembly Top")
		(33 "B.Fab" user "Ref Des/Assembly Bottom")
	)
	(footprint ""
		(layer "F.Cu")
		(at 105.306114 -258.72694 90)
		(property "Reference" "C443"
			(at 0 0 90)
			(layer "F.SilkS")
			(hide yes)
			(effects
				(font
					(size 1.27 1.27)
				)
			)
		)
		(property "Value" ""
			(at 0 0 90)
			(layer "F.Fab")
			(effects
				(font
					(size 1.27 1.27)
				)
			)
		)
		(duplicate_pad_numbers_are_jumpers no)
		(fp_line
			(start 0.7874 -0.4064)
			(end 0.7874 0.4064)
			(stroke
				(width 0.1524)
				(type default)
			)
			(layer "F.SilkS")
		)
		(fp_line
			(start -0.7874 -0.4064)
			(end 0.7874 -0.4064)
			(stroke
				(width 0.1524)
				(type default)
			)
			(layer "F.SilkS")
		)
		(fp_line
			(start 0.7874 0.4064)
			(end -0.7874 0.4064)
			(stroke
				(width 0.1524)
				(type default)
			)
			(layer "F.SilkS")
		)
		(fp_line
			(start -0.7874 0.4064)
			(end -0.7874 -0.4064)
			(stroke
				(width 0.1524)
				(type default)
			)
			(layer "F.SilkS")
		)
		(fp_line
			(start -0.12065 -0.305054)
			(end -0.12065 -0.2794)
			(stroke
				(width 0.1)
				(type default)
			)
			(layer "F.Fab")
		)
		(fp_line
			(start -0.67945 -0.305054)
			(end -0.12065 -0.305054)
			(stroke
				(width 0.1)
				(type default)
			)
			(layer "F.Fab")
		)
		(fp_line
			(start 0.67945 -0.3048)
			(end 0.67945 0.3048)
			(stroke
				(width 0.1)
				(type default)
			)
			(layer "F.Fab")
		)
		(fp_line
			(start 0.12065 -0.3048)
			(end 0.67945 -0.3048)
			(stroke
				(width 0.1)
				(type default)
			)
			(layer "F.Fab")
		)
		(fp_line
			(start 0.12065 -0.2794)
			(end 0.12065 -0.3048)
			(stroke
				(width 0.1)
				(type default)
			)
			(layer "F.Fab")
		)
		(fp_line
			(start -0.12065 -0.2794)
			(end 0.12065 -0.2794)
			(stroke
				(width 0.1)
				(type default)
			)
			(layer "F.Fab")
		)
		(fp_line
			(start 0.120396 0.2794)
			(end -0.12065 0.2794)
			(stroke
				(width 0.1)
				(type default)
			)
			(layer "F.Fab")
		)
		(fp_line
			(start -0.12065 0.2794)
			(end -0.12065 0.3048)
			(stroke
				(width 0.1)
				(type default)
			)
			(layer "F.Fab")
		)
		(fp_line
			(start 0.67945 0.3048)
			(end 0.120396 0.3048)
			(stroke
				(width 0.1)
				(type default)
			)
			(layer "F.Fab")
		)
		(fp_line
			(start 0.120396 0.3048)
			(end 0.120396 0.2794)
			(stroke
				(width 0.1)
				(type default)
			)
			(layer "F.Fab")
		)
		(fp_line
			(start -0.12065 0.3048)
			(end -0.67945 0.3048)
			(stroke
				(width 0.1)
				(type default)
			)
			(layer "F.Fab")
		)
		(fp_line
			(start -0.67945 0.3048)
			(end -0.67945 -0.305054)
			(stroke
				(width 0.1)
				(type default)
			)
			(layer "F.Fab")
		)
		(pad "1" smd circle
			(at -0.40005 0 90)
			(size 0 0)
			(layers "F.Cu" "F.Mask" "F.Paste")
			(net "PVCCFA_EHV_CPU1")
		)
		(pad "2" smd circle
			(at 0.40005 0 90)
			(size 0 0)
			(layers "F.Cu" "F.Mask" "F.Paste")
			(net "GND")
		)
	)
	(footprint ""
		(layer "F.Cu")
		(at 80.31861 -152.381204)
		(property "Reference" "R677"
			(at 0 0 0)
			(layer "F.SilkS")
			(hide yes)
			(effects
				(font
					(size 1.27 1.27)
				)
			)
		)
		(property "Value" ""
			(at 0 0 0)
			(layer "F.Fab")
			(effects
				(font
					(size 1.27 1.27)
				)
			)
		)
		(duplicate_pad_numbers_are_jumpers no)
		(fp_line
			(start -0.7874 -0.4064)
			(end 0.7874 -0.4064)
			(stroke
				(width 0.1524)
				(type default)
			)
			(layer "F.SilkS")
		)
		(fp_line
			(start -0.7874 0.4064)
			(end -0.7874 -0.4064)
			(stroke
				(width 0.1524)
				(type default)
			)
			(layer "F.SilkS")
		)
		(fp_line
			(start 0.7874 -0.4064)
			(end 0.7874 0.4064)
			(stroke
				(width 0.1524)
				(type default)
			)
			(layer "F.SilkS")
		)
		(fp_line
			(start 0.7874 0.4064)
			(end -0.7874 0.4064)
			(stroke
				(width 0.1524)
				(type default)
			)
			(layer "F.SilkS")
		)
		(fp_line
			(start -0.67945 -0.305054)
			(end -0.12065 -0.305054)
			(stroke
				(width 0.1)
				(type default)
			)
			(layer "F.Fab")
		)
		(fp_line
			(start -0.67945 0.3048)
			(end -0.67945 -0.305054)
			(stroke
				(width 0.1)
				(type default)
			)
			(layer "F.Fab")
		)
		(fp_line
			(start -0.12065 -0.305054)
			(end -0.12065 -0.2794)
			(stroke
				(width 0.1)
				(type default)
			)
			(layer "F.Fab")
		)
		(fp_line
			(start -0.12065 -0.2794)
			(end 0.12065 -0.2794)
			(stroke
				(width 0.1)
				(type default)
			)
			(layer "F.Fab")
		)
		(fp_line
			(start -0.12065 0.2794)
			(end -0.12065 0.3048)
			(stroke
				(width 0.1)
				(type default)
			)
			(layer "F.Fab")
		)
		(fp_line
			(start -0.12065 0.3048)
			(end -0.67945 0.3048)
			(stroke
				(width 0.1)
				(type default)
			)
			(layer "F.Fab")
		)
		(fp_line
			(start 0.120396 0.2794)
			(end -0.12065 0.2794)
			(stroke
				(width 0.1)
				(type default)
			)
			(layer "F.Fab")
		)
		(fp_line
			(start 0.120396 0.3048)
			(end 0.120396 0.2794)
			(stroke
				(width 0.1)
				(type default)
			)
			(layer "F.Fab")
		)
		(fp_line
			(start 0.12065 -0.3048)
			(end 0.67945 -0.3048)
			(stroke
				(width 0.1)
				(type default)
			)
			(layer "F.Fab")
		)
		(fp_line
			(start 0.12065 -0.2794)
			(end 0.12065 -0.3048)
			(stroke
				(width 0.1)
				(type default)
			)
			(layer "F.Fab")
		)
		(fp_line
			(start 0.67945 -0.3048)
			(end 0.67945 0.3048)
			(stroke
				(width 0.1)
				(type default)
			)
			(layer "F.Fab")
		)
		(fp_line
			(start 0.67945 0.3048)
			(end 0.120396 0.3048)
			(stroke
				(width 0.1)
				(type default)
			)
			(layer "F.Fab")
		)
		(pad "1" smd circle
			(at -0.40005 0)
			(size 0 0)
			(layers "F.Cu" "F.Mask" "F.Paste")
			(net "I3C_SPD_DDREFGH_CPU1_LVC1_R_SDA")
		)
		(pad "2" smd circle
			(at 0.40005 0)
			(size 0 0)
			(layers "F.Cu" "F.Mask" "F.Paste")
			(net "I3C_SPD_DDREFGH_CPU1_LVC1_SDA")
		)
	)
	(footprint ""
		(layer "F.Cu")
		(at 31.29788 -426.303948)
		(property "Reference" "R3469"
			(at 0 0 0)
			(layer "F.SilkS")
			(hide yes)
			(effects
				(font
					(size 1.27 1.27)
				)
			)
		)
		(property "Value" ""
			(at 0 0 0)
			(layer "F.Fab")
			(effects
				(font
					(size 1.27 1.27)
				)
			)
		)
		(duplicate_pad_numbers_are_jumpers no)
		(fp_line
			(start -0.7874 -0.4064)
			(end 0.7874 -0.4064)
			(stroke
				(width 0.1524)
				(type default)
			)
			(layer "F.SilkS")
		)
		(fp_line
			(start -0.7874 0.4064)
			(end -0.7874 -0.4064)
			(stroke
				(width 0.1524)
				(type default)
			)
			(layer "F.SilkS")
		)
		(fp_line
			(start 0.7874 -0.4064)
			(end 0.7874 0.4064)
			(stroke
				(width 0.1524)
				(type default)
			)
			(layer "F.SilkS")
		)
		(fp_line
			(start 0.7874 0.4064)
			(end -0.7874 0.4064)
			(stroke
				(width 0.1524)
				(type default)
			)
			(layer "F.SilkS")
		)
		(fp_line
			(start -0.67945 -0.305054)
			(end -0.12065 -0.305054)
			(stroke
				(width 0.1)
				(type default)
			)
			(layer "F.Fab")
		)
		(fp_line
			(start -0.67945 0.3048)
			(end -0.67945 -0.305054)
			(stroke
				(width 0.1)
				(type default)
			)
			(layer "F.Fab")
		)
		(fp_line
			(start -0.12065 -0.305054)
			(end -0.12065 -0.2794)
			(stroke
				(width 0.1)
				(type default)
			)
			(layer "F.Fab")
		)
		(fp_line
			(start -0.12065 -0.2794)
			(end 0.12065 -0.2794)
			(stroke
				(width 0.1)
				(type default)
			)
			(layer "F.Fab")
		)
		(fp_line
			(start -0.12065 0.2794)
			(end -0.12065 0.3048)
			(stroke
				(width 0.1)
				(type default)
			)
			(layer "F.Fab")
		)
		(fp_line
			(start -0.12065 0.3048)
			(end -0.67945 0.3048)
			(stroke
				(width 0.1)
				(type default)
			)
			(layer "F.Fab")
		)
		(fp_line
			(start 0.120396 0.2794)
			(end -0.12065 0.2794)
			(stroke
				(width 0.1)
				(type default)
			)
			(layer "F.Fab")
		)
		(fp_line
			(start 0.120396 0.3048)
			(end 0.120396 0.2794)
			(stroke
				(width 0.1)
				(type default)
			)
			(layer "F.Fab")
		)
		(fp_line
			(start 0.12065 -0.3048)
			(end 0.67945 -0.3048)
			(stroke
				(width 0.1)
				(type default)
			)
			(layer "F.Fab")
		)
		(fp_line
			(start 0.12065 -0.2794)
			(end 0.12065 -0.3048)
			(stroke
				(width 0.1)
				(type default)
			)
			(layer "F.Fab")
		)
		(fp_line
			(start 0.67945 -0.3048)
			(end 0.67945 0.3048)
			(stroke
				(width 0.1)
				(type default)
			)
			(layer "F.Fab")
		)
		(fp_line
			(start 0.67945 0.3048)
			(end 0.120396 0.3048)
			(stroke
				(width 0.1)
				(type default)
			)
			(layer "F.Fab")
		)
		(pad "1" smd circle
			(at -0.40005 0)
			(size 0 0)
			(layers "F.Cu" "F.Mask" "F.Paste")
			(net "RST_PERST_0_SWB_BUF_R_N")
		)
		(pad "2" smd circle
			(at 0.40005 0)
			(size 0 0)
			(layers "F.Cu" "F.Mask" "F.Paste")
			(net "RST_PERST_0_SWB_BUF_N")
		)
	)
	(footprint ""
		(layer "F.Cu")
		(at 62.996572 -169.6085 180)
		(property "Reference" "PC381"
			(at 0 0 180)
			(layer "F.SilkS")
			(hide yes)
			(effects
				(font
					(size 1.27 1.27)
				)
			)
		)
		(property "Value" ""
			(at 0 0 180)
			(layer "F.Fab")
			(effects
				(font
					(size 1.27 1.27)
				)
			)
		)
		(duplicate_pad_numbers_are_jumpers no)
		(fp_line
			(start 1.524 0.762)
			(end -1.524 0.762)
			(stroke
				(width 0.1524)
				(type default)
			)
			(layer "F.SilkS")
		)
		(fp_line
			(start 1.524 -0.762)
			(end 1.524 0.762)
			(stroke
				(width 0.1524)
				(type default)
			)
			(layer "F.SilkS")
		)
		(fp_line
			(start -1.524 0.762)
			(end -1.524 -0.762)
			(stroke
				(width 0.1524)
				(type default)
			)
			(layer "F.SilkS")
		)
		(fp_line
			(start -1.524 -0.762)
			(end 1.524 -0.762)
			(stroke
				(width 0.1524)
				(type default)
			)
			(layer "F.SilkS")
		)
		(fp_line
			(start 1.1049 0.724916)
			(end 1.1049 -0.724916)
			(stroke
				(width 0.1)
				(type default)
			)
			(layer "F.Fab")
		)
		(fp_line
			(start 1.1049 -0.724916)
			(end -1.1049 -0.724916)
			(stroke
				(width 0.1)
				(type default)
			)
			(layer "F.Fab")
		)
		(fp_line
			(start -1.1049 0.724916)
			(end 1.1049 0.724916)
			(stroke
				(width 0.1)
				(type default)
			)
			(layer "F.Fab")
		)
		(fp_line
			(start -1.1049 -0.724916)
			(end -1.1049 0.724916)
			(stroke
				(width 0.1)
				(type default)
			)
			(layer "F.Fab")
		)
		(pad "1" smd rect
			(at -0.889 0)
			(size 1.016 1.27)
			(layers "F.Cu" "F.Mask" "F.Paste")
			(net "PVCCD_HV_CPU1")
		)
		(pad "2" smd rect
			(at 0.889 0)
			(size 1.016 1.27)
			(layers "F.Cu" "F.Mask" "F.Paste")
			(net "GND")
		)
	)
	(footprint ""
		(layer "F.Cu")
		(at 77.101954 -342.726264 -90)
		(property "Reference" "PC482_P1_7"
			(at 0 0 270)
			(layer "F.SilkS")
			(hide yes)
			(effects
				(font
					(size 1.27 1.27)
				)
			)
		)
		(property "Value" ""
			(at 0 0 270)
			(layer "F.Fab")
			(effects
				(font
					(size 1.27 1.27)
				)
			)
		)
		(duplicate_pad_numbers_are_jumpers no)
		(fp_line
			(start -0.7874 0.4064)
			(end -0.7874 -0.4064)
			(stroke
				(width 0.1524)
				(type default)
			)
			(layer "F.SilkS")
		)
		(fp_line
			(start 0.7874 0.4064)
			(end -0.7874 0.4064)
			(stroke
				(width 0.1524)
				(type default)
			)
			(layer "F.SilkS")
		)
		(fp_line
			(start -0.7874 -0.4064)
			(end 0.7874 -0.4064)
			(stroke
				(width 0.1524)
				(type default)
			)
			(layer "F.SilkS")
		)
		(fp_line
			(start 0.7874 -0.4064)
			(end 0.7874 0.4064)
			(stroke
				(width 0.1524)
				(type default)
			)
			(layer "F.SilkS")
		)
		(fp_line
			(start -0.67945 0.3048)
			(end -0.67945 -0.305054)
			(stroke
				(width 0.1)
				(type default)
			)
			(layer "F.Fab")
		)
		(fp_line
			(start -0.12065 0.3048)
			(end -0.67945 0.3048)
			(stroke
				(width 0.1)
				(type default)
			)
			(layer "F.Fab")
		)
		(fp_line
			(start 0.120396 0.3048)
			(end 0.120396 0.2794)
			(stroke
				(width 0.1)
				(type default)
			)
			(layer "F.Fab")
		)
		(fp_line
			(start 0.67945 0.3048)
			(end 0.120396 0.3048)
			(stroke
				(width 0.1)
				(type default)
			)
			(layer "F.Fab")
		)
		(fp_line
			(start -0.12065 0.2794)
			(end -0.12065 0.3048)
			(stroke
				(width 0.1)
				(type default)
			)
			(layer "F.Fab")
		)
		(fp_line
			(start 0.120396 0.2794)
			(end -0.12065 0.2794)
			(stroke
				(width 0.1)
				(type default)
			)
			(layer "F.Fab")
		)
		(fp_line
			(start -0.12065 -0.2794)
			(end 0.12065 -0.2794)
			(stroke
				(width 0.1)
				(type default)
			)
			(layer "F.Fab")
		)
		(fp_line
			(start 0.12065 -0.2794)
			(end 0.12065 -0.3048)
			(stroke
				(width 0.1)
				(type default)
			)
			(layer "F.Fab")
		)
		(fp_line
			(start 0.12065 -0.3048)
			(end 0.67945 -0.3048)
			(stroke
				(width 0.1)
				(type default)
			)
			(layer "F.Fab")
		)
		(fp_line
			(start 0.67945 -0.3048)
			(end 0.67945 0.3048)
			(stroke
				(width 0.1)
				(type default)
			)
			(layer "F.Fab")
		)
		(fp_line
			(start -0.67945 -0.305054)
			(end -0.12065 -0.305054)
			(stroke
				(width 0.1)
				(type default)
			)
			(layer "F.Fab")
		)
		(fp_line
			(start -0.12065 -0.305054)
			(end -0.12065 -0.2794)
			(stroke
				(width 0.1)
				(type default)
			)
			(layer "F.Fab")
		)
		(pad "1" smd circle
			(at -0.40005 0 270)
			(size 0 0)
			(layers "F.Cu" "F.Mask" "F.Paste")
			(net "PVCCIN_CPU1_PVCC")
		)
		(pad "2" smd circle
			(at 0.40005 0 270)
			(size 0 0)
			(layers "F.Cu" "F.Mask" "F.Paste")
			(net "GND")
		)
	)
	(footprint ""
		(layer "F.Cu")
		(at 304.1396 -419.10635 -90)
		(property "Reference" "C2264"
			(at 0 0 270)
			(layer "F.SilkS")
			(hide yes)
			(effects
				(font
					(size 1.27 1.27)
				)
			)
		)
		(property "Value" ""
			(at 0 0 270)
			(layer "F.Fab")
			(effects
				(font
					(size 1.27 1.27)
				)
			)
		)
		(duplicate_pad_numbers_are_jumpers no)
		(fp_line
			(start -0.7874 0.4064)
			(end -0.7874 -0.4064)
			(stroke
				(width 0.1524)
				(type default)
			)
			(layer "F.SilkS")
		)
		(fp_line
			(start 0.7874 0.4064)
			(end -0.7874 0.4064)
			(stroke
				(width 0.1524)
				(type default)
			)
			(layer "F.SilkS")
		)
		(fp_line
			(start -0.7874 -0.4064)
			(end 0.7874 -0.4064)
			(stroke
				(width 0.1524)
				(type default)
			)
			(layer "F.SilkS")
		)
		(fp_line
			(start 0.7874 -0.4064)
			(end 0.7874 0.4064)
			(stroke
				(width 0.1524)
				(type default)
			)
			(layer "F.SilkS")
		)
		(fp_line
			(start -0.67945 0.3048)
			(end -0.67945 -0.305054)
			(stroke
				(width 0.1)
				(type default)
			)
			(layer "F.Fab")
		)
		(fp_line
			(start -0.12065 0.3048)
			(end -0.67945 0.3048)
			(stroke
				(width 0.1)
				(type default)
			)
			(layer "F.Fab")
		)
		(fp_line
			(start 0.120396 0.3048)
			(end 0.120396 0.2794)
			(stroke
				(width 0.1)
				(type default)
			)
			(layer "F.Fab")
		)
		(fp_line
			(start 0.67945 0.3048)
			(end 0.120396 0.3048)
			(stroke
				(width 0.1)
				(type default)
			)
			(layer "F.Fab")
		)
		(fp_line
			(start -0.12065 0.2794)
			(end -0.12065 0.3048)
			(stroke
				(width 0.1)
				(type default)
			)
			(layer "F.Fab")
		)
		(fp_line
			(start 0.120396 0.2794)
			(end -0.12065 0.2794)
			(stroke
				(width 0.1)
				(type default)
			)
			(layer "F.Fab")
		)
		(fp_line
			(start -0.12065 -0.2794)
			(end 0.12065 -0.2794)
			(stroke
				(width 0.1)
				(type default)
			)
			(layer "F.Fab")
		)
		(fp_line
			(start 0.12065 -0.2794)
			(end 0.12065 -0.3048)
			(stroke
				(width 0.1)
				(type default)
			)
			(layer "F.Fab")
		)
		(fp_line
			(start 0.12065 -0.3048)
			(end 0.67945 -0.3048)
			(stroke
				(width 0.1)
				(type default)
			)
			(layer "F.Fab")
		)
		(fp_line
			(start 0.67945 -0.3048)
			(end 0.67945 0.3048)
			(stroke
				(width 0.1)
				(type default)
			)
			(layer "F.Fab")
		)
		(fp_line
			(start -0.67945 -0.305054)
			(end -0.12065 -0.305054)
			(stroke
				(width 0.1)
				(type default)
			)
			(layer "F.Fab")
		)
		(fp_line
			(start -0.12065 -0.305054)
			(end -0.12065 -0.2794)
			(stroke
				(width 0.1)
				(type default)
			)
			(layer "F.Fab")
		)
		(pad "1" smd circle
			(at -0.40005 0 270)
			(size 0 0)
			(layers "F.Cu" "F.Mask" "F.Paste")
			(net "GPU_3V3IO_RSVD0_FFU_ISO")
		)
		(pad "2" smd circle
			(at 0.40005 0 270)
			(size 0 0)
			(layers "F.Cu" "F.Mask" "F.Paste")
			(net "GND")
		)
	)
)
